(kicad_pcb
	(version 20260206)
	(generator "pcbnew")
	(generator_version "10.0")
	(general
		(thickness 1.6)
		(legacy_teardrops no)
	)
	(paper "A4")
	(title_block
		(title "9052_F0T_PDB_Converter_Brick_F_V03_1208_1600_OCP.brd")
		(comment 1 "Grand Teton / footprints 224-231 of 578")
	)
	(layers
		(0 "F.Cu" signal "TOP")
		(4 "In1.Cu" signal "GND")
		(6 "In2.Cu" signal "IN1")
		(8 "In3.Cu" signal "GND1")
		(10 "In4.Cu" signal "VCC")
		(12 "In5.Cu" signal "VCC1")
		(14 "In6.Cu" signal "GND2")
		(16 "In7.Cu" signal "IN2")
		(18 "In8.Cu" signal "GND3")
		(2 "B.Cu" signal "BOTTOM")
		(9 "F.Adhes" user "F.Adhesive")
		(11 "B.Adhes" user "B.Adhesive")
		(13 "F.Paste" user "Package Geometry/Pastemask Top")
		(15 "B.Paste" user "Package Geometry/Pastemask Bottom")
		(5 "F.SilkS" user "Ref Des/Silkscreen Top")
		(7 "B.SilkS" user "Ref Des/Silkscreen Bottom")
		(1 "F.Mask" user "Board Geometry/Soldermask Top")
		(3 "B.Mask" user "Board Geometry/Soldermask Bottom")
		(17 "Dwgs.User" user "User.Drawings")
		(19 "Cmts.User" user "User.Comments")
		(21 "Eco1.User" user "User.Eco1")
		(23 "Eco2.User" user "User.Eco2")
		(25 "Edge.Cuts" user "Board Geometry/Outline")
		(27 "Margin" user)
		(31 "F.CrtYd" user "Package Geometry/Place Bound Top")
		(29 "B.CrtYd" user "Package Geometry/Place Bound Bottom")
		(35 "F.Fab" user "Ref Des/Assembly Top")
		(33 "B.Fab" user "Ref Des/Assembly Bottom")
	)
	(footprint ""
		(layer "F.Cu")
		(at 40.781478 -61.24956)
		(property "Reference" "R5899"
			(at 0 0 0)
			(layer "F.SilkS")
			(hide yes)
			(effects
				(font
					(size 1.27 1.27)
				)
			)
		)
		(property "Value" ""
			(at 0 0 0)
			(layer "F.Fab")
			(effects
				(font
					(size 1.27 1.27)
				)
			)
		)
		(duplicate_pad_numbers_are_jumpers no)
		(fp_line
			(start -0.7874 -0.4064)
			(end 0.7874 -0.4064)
			(stroke
				(width 0.1524)
				(type default)
			)
			(layer "F.SilkS")
		)
		(fp_line
			(start -0.7874 0.4064)
			(end -0.7874 -0.4064)
			(stroke
				(width 0.1524)
				(type default)
			)
			(layer "F.SilkS")
		)
		(fp_line
			(start 0.7874 -0.4064)
			(end 0.7874 0.4064)
			(stroke
				(width 0.1524)
				(type default)
			)
			(layer "F.SilkS")
		)
		(fp_line
			(start 0.7874 0.4064)
			(end -0.7874 0.4064)
			(stroke
				(width 0.1524)
				(type default)
			)
			(layer "F.SilkS")
		)
		(fp_line
			(start -0.67945 -0.305054)
			(end -0.12065 -0.305054)
			(stroke
				(width 0.1)
				(type default)
			)
			(layer "F.Fab")
		)
		(fp_line
			(start -0.67945 0.3048)
			(end -0.67945 -0.305054)
			(stroke
				(width 0.1)
				(type default)
			)
			(layer "F.Fab")
		)
		(fp_line
			(start -0.12065 -0.305054)
			(end -0.12065 -0.2794)
			(stroke
				(width 0.1)
				(type default)
			)
			(layer "F.Fab")
		)
		(fp_line
			(start -0.12065 -0.2794)
			(end 0.12065 -0.2794)
			(stroke
				(width 0.1)
				(type default)
			)
			(layer "F.Fab")
		)
		(fp_line
			(start -0.12065 0.2794)
			(end -0.12065 0.3048)
			(stroke
				(width 0.1)
				(type default)
			)
			(layer "F.Fab")
		)
		(fp_line
			(start -0.12065 0.3048)
			(end -0.67945 0.3048)
			(stroke
				(width 0.1)
				(type default)
			)
			(layer "F.Fab")
		)
		(fp_line
			(start 0.120396 0.2794)
			(end -0.12065 0.2794)
			(stroke
				(width 0.1)
				(type default)
			)
			(layer "F.Fab")
		)
		(fp_line
			(start 0.120396 0.3048)
			(end 0.120396 0.2794)
			(stroke
				(width 0.1)
				(type default)
			)
			(layer "F.Fab")
		)
		(fp_line
			(start 0.12065 -0.3048)
			(end 0.67945 -0.3048)
			(stroke
				(width 0.1)
				(type default)
			)
			(layer "F.Fab")
		)
		(fp_line
			(start 0.12065 -0.2794)
			(end 0.12065 -0.3048)
			(stroke
				(width 0.1)
				(type default)
			)
			(layer "F.Fab")
		)
		(fp_line
			(start 0.67945 -0.3048)
			(end 0.67945 0.3048)
			(stroke
				(width 0.1)
				(type default)
			)
			(layer "F.Fab")
		)
		(fp_line
			(start 0.67945 0.3048)
			(end 0.120396 0.3048)
			(stroke
				(width 0.1)
				(type default)
			)
			(layer "F.Fab")
		)
		(pad "1" smd circle
			(at -0.40005 0)
			(size 0 0)
			(layers "F.Cu" "F.Mask" "F.Paste")
			(net "GND")
		)
		(pad "2" smd circle
			(at 0.40005 0)
			(size 0 0)
			(layers "F.Cu" "F.Mask" "F.Paste")
			(net "P12V_HPDB_0_FB")
		)
	)
	(footprint ""
		(layer "F.Cu")
		(at 276.802088 -34.49447 90)
		(property "Reference" "R5932"
			(at 0 0 90)
			(layer "F.SilkS")
			(hide yes)
			(effects
				(font
					(size 1.27 1.27)
				)
			)
		)
		(property "Value" ""
			(at 0 0 90)
			(layer "F.Fab")
			(effects
				(font
					(size 1.27 1.27)
				)
			)
		)
		(duplicate_pad_numbers_are_jumpers no)
		(fp_line
			(start 1.651 -0.8382)
			(end 1.651 0.8382)
			(stroke
				(width 0.1524)
				(type default)
			)
			(layer "F.SilkS")
		)
		(fp_line
			(start -1.651 -0.8382)
			(end 1.651 -0.8382)
			(stroke
				(width 0.1524)
				(type default)
			)
			(layer "F.SilkS")
		)
		(fp_line
			(start 1.651 0.8382)
			(end -1.651 0.8382)
			(stroke
				(width 0.1524)
				(type default)
			)
			(layer "F.SilkS")
		)
		(fp_line
			(start -1.651 0.8382)
			(end -1.651 -0.8382)
			(stroke
				(width 0.1524)
				(type default)
			)
			(layer "F.SilkS")
		)
		(fp_line
			(start 1.560576 -0.7366)
			(end 1.524 -0.7366)
			(stroke
				(width 0.1)
				(type default)
			)
			(layer "F.Fab")
		)
		(fp_line
			(start 1.524 -0.7366)
			(end -1.524 -0.7366)
			(stroke
				(width 0.1)
				(type default)
			)
			(layer "F.Fab")
		)
		(fp_line
			(start -1.524 -0.7366)
			(end -1.559814 -0.7366)
			(stroke
				(width 0.1)
				(type default)
			)
			(layer "F.Fab")
		)
		(fp_line
			(start -1.559814 -0.7366)
			(end -1.559814 0.7366)
			(stroke
				(width 0.1)
				(type default)
			)
			(layer "F.Fab")
		)
		(fp_line
			(start 1.560576 0.7366)
			(end 1.560576 -0.7366)
			(stroke
				(width 0.1)
				(type default)
			)
			(layer "F.Fab")
		)
		(fp_line
			(start 1.524 0.7366)
			(end 1.560576 0.7366)
			(stroke
				(width 0.1)
				(type default)
			)
			(layer "F.Fab")
		)
		(fp_line
			(start -1.524 0.7366)
			(end 1.524 0.7366)
			(stroke
				(width 0.1)
				(type default)
			)
			(layer "F.Fab")
		)
		(fp_line
			(start -1.559814 0.7366)
			(end -1.524 0.7366)
			(stroke
				(width 0.1)
				(type default)
			)
			(layer "F.Fab")
		)
		(pad "1" smd rect
			(at -0.94996 0 270)
			(size 1.1176 1.3716)
			(layers "F.Cu" "F.Mask" "F.Paste")
			(net "P52V_1_R")
		)
		(pad "2" smd rect
			(at 0.94996 0 270)
			(size 1.1176 1.3716)
			(layers "F.Cu" "F.Mask" "F.Paste")
			(net "P52V_HS1_EN_BUF_DELAY")
		)
	)
	(footprint ""
		(layer "F.Cu")
		(at 134.239 -136.906 90)
		(property "Reference" "PC16"
			(at 6.19633 1.143 0)
			(unlocked yes)
			(layer "F.SilkS")
			(effects
				(font
					(size 0.7874 0.5842)
					(thickness 0.1524)
				)
				(justify left)
			)
		)
		(property "Value" ""
			(at 0 0 90)
			(layer "F.Fab")
			(effects
				(font
					(size 1.27 1.27)
				)
			)
		)
		(duplicate_pad_numbers_are_jumpers no)
		(fp_line
			(start 5.2578 2.499868)
			(end -5.2578 2.499868)
			(stroke
				(width 0.1524)
				(type default)
			)
			(layer "F.SilkS")
		)
		(fp_circle
			(center 0 2.500122)
			(end 0 7.758176)
			(stroke
				(width 0.1524)
				(type default)
			)
			(fill no)
			(layer "F.SilkS")
		)
		(fp_poly
			(pts
				(arc
					(start 5.2578 2.499868)
					(mid 0 7.757922)
					(end -5.2578 2.499868)
				)
			)
			(stroke
				(width 0)
				(type default)
			)
			(fill yes)
			(layer "F.SilkS")
		)
		(fp_circle
			(center 0 2.500122)
			(end 0 7.758176)
			(stroke
				(width 0.1)
				(type default)
			)
			(fill no)
			(layer "F.Fab")
		)
		(pad "1" thru_hole rect
			(at 0 0)
			(size 1.5748 1.5748)
			(drill 1.0668)
			(layers "*.Cu" "*.Mask")
			(remove_unused_layers no)
			(net "P52V_HS_FILTER")
			(clearance 0)
			(padstack
				(mode front_inner_back)
				(layer "Inner"
					(shape circle)
					(size 1.5748 1.5748)
					(clearance 0)
				)
				(layer "B.Cu"
					(shape rect)
					(size 1.5748 1.5748)
					(clearance 0)
				)
			)
		)
		(pad "2" thru_hole circle
			(at 0 4.99999)
			(size 1.5748 1.5748)
			(drill 1.0668)
			(layers "*.Cu" "*.Mask")
			(remove_unused_layers no)
			(net "GND")
			(clearance 0)
		)
	)
	(footprint ""
		(layer "F.Cu")
		(at 179.065174 -60.325)
		(property "Reference" "PR321"
			(at 0 0 0)
			(layer "F.SilkS")
			(hide yes)
			(effects
				(font
					(size 1.27 1.27)
				)
			)
		)
		(property "Value" ""
			(at 0 0 0)
			(layer "F.Fab")
			(effects
				(font
					(size 1.27 1.27)
				)
			)
		)
		(duplicate_pad_numbers_are_jumpers no)
		(fp_line
			(start -1.651 -0.8382)
			(end 1.651 -0.8382)
			(stroke
				(width 0.1524)
				(type default)
			)
			(layer "F.SilkS")
		)
		(fp_line
			(start -1.651 0.8382)
			(end -1.651 -0.8382)
			(stroke
				(width 0.1524)
				(type default)
			)
			(layer "F.SilkS")
		)
		(fp_line
			(start 1.651 -0.8382)
			(end 1.651 0.8382)
			(stroke
				(width 0.1524)
				(type default)
			)
			(layer "F.SilkS")
		)
		(fp_line
			(start 1.651 0.8382)
			(end -1.651 0.8382)
			(stroke
				(width 0.1524)
				(type default)
			)
			(layer "F.SilkS")
		)
		(fp_line
			(start -1.559814 -0.7366)
			(end -1.559814 0.7366)
			(stroke
				(width 0.1)
				(type default)
			)
			(layer "F.Fab")
		)
		(fp_line
			(start -1.559814 0.7366)
			(end -1.524 0.7366)
			(stroke
				(width 0.1)
				(type default)
			)
			(layer "F.Fab")
		)
		(fp_line
			(start -1.524 -0.7366)
			(end -1.559814 -0.7366)
			(stroke
				(width 0.1)
				(type default)
			)
			(layer "F.Fab")
		)
		(fp_line
			(start -1.524 0.7366)
			(end 1.524 0.7366)
			(stroke
				(width 0.1)
				(type default)
			)
			(layer "F.Fab")
		)
		(fp_line
			(start 1.524 -0.7366)
			(end -1.524 -0.7366)
			(stroke
				(width 0.1)
				(type default)
			)
			(layer "F.Fab")
		)
		(fp_line
			(start 1.524 0.7366)
			(end 1.560576 0.7366)
			(stroke
				(width 0.1)
				(type default)
			)
			(layer "F.Fab")
		)
		(fp_line
			(start 1.560576 -0.7366)
			(end 1.524 -0.7366)
			(stroke
				(width 0.1)
				(type default)
			)
			(layer "F.Fab")
		)
		(fp_line
			(start 1.560576 0.7366)
			(end 1.560576 -0.7366)
			(stroke
				(width 0.1)
				(type default)
			)
			(layer "F.Fab")
		)
		(pad "1" smd rect
			(at -0.94996 0 180)
			(size 1.1176 1.3716)
			(layers "F.Cu" "F.Mask" "F.Paste")
			(net "P12V_BRICK")
		)
		(pad "2" smd rect
			(at 0.94996 0 180)
			(size 1.1176 1.3716)
			(layers "F.Cu" "F.Mask" "F.Paste")
			(net "GND")
		)
	)
	(footprint ""
		(layer "F.Cu")
		(at 191.643 -10.922)
		(property "Reference" "PC106"
			(at 0 0 0)
			(layer "F.SilkS")
			(hide yes)
			(effects
				(font
					(size 1.27 1.27)
				)
			)
		)
		(property "Value" ""
			(at 0 0 0)
			(layer "F.Fab")
			(effects
				(font
					(size 1.27 1.27)
				)
			)
		)
		(duplicate_pad_numbers_are_jumpers no)
		(fp_line
			(start -1.524 -0.762)
			(end 1.524 -0.762)
			(stroke
				(width 0.1524)
				(type default)
			)
			(layer "F.SilkS")
		)
		(fp_line
			(start -1.524 0.762)
			(end -1.524 -0.762)
			(stroke
				(width 0.1524)
				(type default)
			)
			(layer "F.SilkS")
		)
		(fp_line
			(start 1.524 -0.762)
			(end 1.524 0.762)
			(stroke
				(width 0.1524)
				(type default)
			)
			(layer "F.SilkS")
		)
		(fp_line
			(start 1.524 0.762)
			(end -1.524 0.762)
			(stroke
				(width 0.1524)
				(type default)
			)
			(layer "F.SilkS")
		)
		(fp_line
			(start -1.1049 -0.724916)
			(end -1.1049 0.724916)
			(stroke
				(width 0.1)
				(type default)
			)
			(layer "F.Fab")
		)
		(fp_line
			(start -1.1049 0.724916)
			(end 1.1049 0.724916)
			(stroke
				(width 0.1)
				(type default)
			)
			(layer "F.Fab")
		)
		(fp_line
			(start 1.1049 -0.724916)
			(end -1.1049 -0.724916)
			(stroke
				(width 0.1)
				(type default)
			)
			(layer "F.Fab")
		)
		(fp_line
			(start 1.1049 0.724916)
			(end 1.1049 -0.724916)
			(stroke
				(width 0.1)
				(type default)
			)
			(layer "F.Fab")
		)
		(pad "1" smd rect
			(at -0.889 0 180)
			(size 1.016 1.27)
			(layers "F.Cu" "F.Mask" "F.Paste")
			(net "P3V3_AUX")
		)
		(pad "2" smd rect
			(at 0.889 0 180)
			(size 1.016 1.27)
			(layers "F.Cu" "F.Mask" "F.Paste")
			(net "GND")
		)
	)
	(footprint ""
		(layer "F.Cu")
		(at 189.098174 -130.175)
		(property "Reference" "PC116"
			(at 0 0 0)
			(layer "F.SilkS")
			(hide yes)
			(effects
				(font
					(size 1.27 1.27)
				)
			)
		)
		(property "Value" ""
			(at 0 0 0)
			(layer "F.Fab")
			(effects
				(font
					(size 1.27 1.27)
				)
			)
		)
		(duplicate_pad_numbers_are_jumpers no)
		(fp_line
			(start -2.2098 -0.9398)
			(end 2.2098 -0.9398)
			(stroke
				(width 0.1524)
				(type default)
			)
			(layer "F.SilkS")
		)
		(fp_line
			(start -2.2098 0.9398)
			(end -2.2098 -0.9398)
			(stroke
				(width 0.1524)
				(type default)
			)
			(layer "F.SilkS")
		)
		(fp_line
			(start 2.2098 -0.9398)
			(end 2.2098 0.9398)
			(stroke
				(width 0.1524)
				(type default)
			)
			(layer "F.SilkS")
		)
		(fp_line
			(start 2.2098 0.9398)
			(end -2.2098 0.9398)
			(stroke
				(width 0.1524)
				(type default)
			)
			(layer "F.SilkS")
		)
		(fp_line
			(start -1.700022 -0.899922)
			(end 1.700022 -0.899922)
			(stroke
				(width 0.1)
				(type default)
			)
			(layer "F.Fab")
		)
		(fp_line
			(start -1.700022 0.899922)
			(end -1.700022 -0.899922)
			(stroke
				(width 0.1)
				(type default)
			)
			(layer "F.Fab")
		)
		(fp_line
			(start 1.700022 -0.899922)
			(end 1.700022 0.899922)
			(stroke
				(width 0.1)
				(type default)
			)
			(layer "F.Fab")
		)
		(fp_line
			(start 1.700022 0.899922)
			(end -1.700022 0.899922)
			(stroke
				(width 0.1)
				(type default)
			)
			(layer "F.Fab")
		)
		(pad "1" smd rect
			(at -1.4732 0 180)
			(size 1.1684 1.5748)
			(layers "F.Cu" "F.Mask" "F.Paste")
			(net "P52V_HS_FILTER")
		)
		(pad "2" smd rect
			(at 1.4732 0 180)
			(size 1.1684 1.5748)
			(layers "F.Cu" "F.Mask" "F.Paste")
			(net "GND")
		)
	)
	(footprint ""
		(layer "F.Cu")
		(at 301.602394 -85.2805 180)
		(property "Reference" "PR6964"
			(at 0 0 180)
			(layer "F.SilkS")
			(hide yes)
			(effects
				(font
					(size 1.27 1.27)
				)
			)
		)
		(property "Value" ""
			(at 0 0 180)
			(layer "F.Fab")
			(effects
				(font
					(size 1.27 1.27)
				)
			)
		)
		(duplicate_pad_numbers_are_jumpers no)
		(fp_line
			(start 1.2954 0.5842)
			(end -1.2954 0.5842)
			(stroke
				(width 0.1524)
				(type default)
			)
			(layer "F.SilkS")
		)
		(fp_line
			(start 1.2954 -0.5842)
			(end 1.2954 0.5842)
			(stroke
				(width 0.1524)
				(type default)
			)
			(layer "F.SilkS")
		)
		(fp_line
			(start -1.2954 0.5842)
			(end -1.2954 -0.5842)
			(stroke
				(width 0.1524)
				(type default)
			)
			(layer "F.SilkS")
		)
		(fp_line
			(start -1.2954 -0.5842)
			(end 1.2954 -0.5842)
			(stroke
				(width 0.1524)
				(type default)
			)
			(layer "F.SilkS")
		)
		(fp_line
			(start 1.1938 0.4064)
			(end 0.8636 0.4064)
			(stroke
				(width 0.1)
				(type default)
			)
			(layer "F.Fab")
		)
		(fp_line
			(start 1.1938 -0.406654)
			(end 1.1938 0.4064)
			(stroke
				(width 0.1)
				(type default)
			)
			(layer "F.Fab")
		)
		(fp_line
			(start 0.8636 0.4572)
			(end -0.8636 0.4572)
			(stroke
				(width 0.1)
				(type default)
			)
			(layer "F.Fab")
		)
		(fp_line
			(start 0.8636 0.4064)
			(end 0.8636 0.4572)
			(stroke
				(width 0.1)
				(type default)
			)
			(layer "F.Fab")
		)
		(fp_line
			(start 0.8636 -0.406654)
			(end 1.1938 -0.406654)
			(stroke
				(width 0.1)
				(type default)
			)
			(layer "F.Fab")
		)
		(fp_line
			(start 0.8636 -0.4572)
			(end 0.8636 -0.406654)
			(stroke
				(width 0.1)
				(type default)
			)
			(layer "F.Fab")
		)
		(fp_line
			(start -0.8636 0.4572)
			(end -0.8636 0.4318)
			(stroke
				(width 0.1)
				(type default)
			)
			(layer "F.Fab")
		)
		(fp_line
			(start -0.8636 0.4318)
			(end -0.8636 0.4064)
			(stroke
				(width 0.1)
				(type default)
			)
			(layer "F.Fab")
		)
		(fp_line
			(start -0.8636 0.4064)
			(end -1.1938 0.4064)
			(stroke
				(width 0.1)
				(type default)
			)
			(layer "F.Fab")
		)
		(fp_line
			(start -0.8636 -0.406654)
			(end -0.8636 -0.4572)
			(stroke
				(width 0.1)
				(type default)
			)
			(layer "F.Fab")
		)
		(fp_line
			(start -0.8636 -0.4572)
			(end 0.8636 -0.4572)
			(stroke
				(width 0.1)
				(type default)
			)
			(layer "F.Fab")
		)
		(fp_line
			(start -1.1938 0.4064)
			(end -1.1938 -0.406654)
			(stroke
				(width 0.1)
				(type default)
			)
			(layer "F.Fab")
		)
		(fp_line
			(start -1.1938 -0.406654)
			(end -0.8636 -0.406654)
			(stroke
				(width 0.1)
				(type default)
			)
			(layer "F.Fab")
		)
		(pad "1" smd rect
			(at -0.7366 0 90)
			(size 0.7112 0.8128)
			(layers "F.Cu" "F.Mask" "F.Paste")
			(net "P52V_HS1_SENSE_P_R2")
		)
		(pad "2" smd rect
			(at 0.7366 0 90)
			(size 0.7112 0.8128)
			(layers "F.Cu" "F.Mask" "F.Paste")
			(net "P52V_HS_4287_ADC_P")
		)
	)
	(footprint ""
		(layer "F.Cu")
		(at 191.643 -13.081)
		(property "Reference" "PC107"
			(at 0 0 0)
			(layer "F.SilkS")
			(hide yes)
			(effects
				(font
					(size 1.27 1.27)
				)
			)
		)
		(property "Value" ""
			(at 0 0 0)
			(layer "F.Fab")
			(effects
				(font
					(size 1.27 1.27)
				)
			)
		)
		(duplicate_pad_numbers_are_jumpers no)
		(fp_line
			(start -1.524 -0.762)
			(end 1.524 -0.762)
			(stroke
				(width 0.1524)
				(type default)
			)
			(layer "F.SilkS")
		)
		(fp_line
			(start -1.524 0.762)
			(end -1.524 -0.762)
			(stroke
				(width 0.1524)
				(type default)
			)
			(layer "F.SilkS")
		)
		(fp_line
			(start 1.524 -0.762)
			(end 1.524 0.762)
			(stroke
				(width 0.1524)
				(type default)
			)
			(layer "F.SilkS")
		)
		(fp_line
			(start 1.524 0.762)
			(end -1.524 0.762)
			(stroke
				(width 0.1524)
				(type default)
			)
			(layer "F.SilkS")
		)
		(fp_line
			(start -1.1049 -0.724916)
			(end -1.1049 0.724916)
			(stroke
				(width 0.1)
				(type default)
			)
			(layer "F.Fab")
		)
		(fp_line
			(start -1.1049 0.724916)
			(end 1.1049 0.724916)
			(stroke
				(width 0.1)
				(type default)
			)
			(layer "F.Fab")
		)
		(fp_line
			(start 1.1049 -0.724916)
			(end -1.1049 -0.724916)
			(stroke
				(width 0.1)
				(type default)
			)
			(layer "F.Fab")
		)
		(fp_line
			(start 1.1049 0.724916)
			(end 1.1049 -0.724916)
			(stroke
				(width 0.1)
				(type default)
			)
			(layer "F.Fab")
		)
		(pad "1" smd rect
			(at -0.889 0 180)
			(size 1.016 1.27)
			(layers "F.Cu" "F.Mask" "F.Paste")
			(net "P3V3_AUX")
		)
		(pad "2" smd rect
			(at 0.889 0 180)
			(size 1.016 1.27)
			(layers "F.Cu" "F.Mask" "F.Paste")
			(net "GND")
		)
	)
)
